(kicad_pcb
	(version 20241229)
	(generator "pcbnew")
	(generator_version "9.0")
	(general
		(thickness 1.599998)
		(legacy_teardrops no)
	)
	(paper "A4")
	(title_block
		(date "2023-02-12")
		(rev "1.1.5")
		(comment 9 "footprints 333-338 of 473")
	)
	(layers
		(0 "F.Cu" signal)
		(4 "In1.Cu" power "In1.GND")
		(6 "In2.Cu" signal)
		(8 "In3.Cu" power "In3.GND")
		(10 "In4.Cu" power "In4.VCC")
		(12 "In5.Cu" signal)
		(14 "In6.Cu" power "In6.VCC")
		(2 "B.Cu" signal)
		(9 "F.Adhes" user "F.Adhesive")
		(11 "B.Adhes" user "B.Adhesive")
		(13 "F.Paste" user)
		(15 "B.Paste" user)
		(5 "F.SilkS" user "F.Silkscreen")
		(7 "B.SilkS" user "B.Silkscreen")
		(1 "F.Mask" user)
		(3 "B.Mask" user)
		(17 "Dwgs.User" user "User.Drawings")
		(19 "Cmts.User" user "User.Comments")
		(21 "Eco1.User" user "User.Eco1")
		(23 "Eco2.User" user "User.Eco2")
		(25 "Edge.Cuts" user)
		(27 "Margin" user)
		(31 "F.CrtYd" user "F.Courtyard")
		(29 "B.CrtYd" user "B.Courtyard")
		(35 "F.Fab" user)
		(33 "B.Fab" user)
	)
	(footprint "antmicro-footprints:C_0201"
		(layer "B.Cu")
		(at 165.536328 95.622157)
		(descr "Capacitor SMD 0201")
		(tags "capacitor SMD 0201")
		(property "Reference" "C45"
			(at 0.963672 -0.322157 180)
			(layer "B.SilkS")
			(effects
				(font
					(size 0.7 0.7)
					(thickness 0.15)
				)
				(justify left bottom mirror)
			)
		)
		(property "Value" "C_100n_0201"
			(at 0 -1.4 180)
			(layer "B.Fab")
			(effects
				(font
					(size 0.7 0.7)
					(thickness 0.15)
				)
				(justify left bottom mirror)
			)
		)
		(property "Description" " "
			(at 0 0 0)
			(layer "F.Fab")
			(hide yes)
			(effects
				(font
					(size 1.27 1.27)
					(thickness 0.15)
				)
			)
		)
		(property "Author" "Antmicro"
			(at 0 0 0)
			(layer "B.Fab")
			(hide yes)
			(effects
				(font
					(size 1 1)
					(thickness 0.15)
				)
				(justify mirror)
			)
		)
		(property "Dielectric" ""
			(at 0 0 0)
			(layer "B.Fab")
			(hide yes)
			(effects
				(font
					(size 1 1)
					(thickness 0.15)
				)
				(justify mirror)
			)
		)
		(property "License" "Apache-2.0"
			(at 0 0 0)
			(layer "B.Fab")
			(hide yes)
			(effects
				(font
					(size 1 1)
					(thickness 0.15)
				)
				(justify mirror)
			)
		)
		(property "MPN" "CC0201KRX6S5BB104"
			(at 0 0 0)
			(layer "B.Fab")
			(hide yes)
			(effects
				(font
					(size 1 1)
					(thickness 0.15)
				)
				(justify mirror)
			)
		)
		(property "Manufacturer" "Yaego"
			(at 0 0 0)
			(layer "B.Fab")
			(hide yes)
			(effects
				(font
					(size 1 1)
					(thickness 0.15)
				)
				(justify mirror)
			)
		)
		(property "Val" "100n"
			(at 0 0 0)
			(layer "B.Fab")
			(hide yes)
			(effects
				(font
					(size 1 1)
					(thickness 0.15)
				)
				(justify mirror)
			)
		)
		(property "Voltage" ""
			(at 0 0 0)
			(layer "B.Fab")
			(hide yes)
			(effects
				(font
					(size 1 1)
					(thickness 0.15)
				)
				(justify mirror)
			)
		)
		(sheetname "FPGA power")
		(sheetfile "fpga-power.kicad_sch")
		(attr smd)
		(fp_rect
			(start -0.72 0.38)
			(end 0.72 -0.38)
			(stroke
				(width 0.05)
				(type solid)
			)
			(fill no)
			(layer "B.CrtYd")
		)
		(fp_rect
			(start 0.3 -0.15)
			(end -0.301 0.149)
			(stroke
				(width 0.15)
				(type solid)
			)
			(fill no)
			(layer "B.Fab")
		)
		(pad "" smd roundrect
			(at -0.349 0.002)
			(size 0.318 0.36)
			(layers "B.Paste")
			(roundrect_rratio 0.25)
		)
		(pad "" smd roundrect
			(at 0.341 0.002)
			(size 0.318 0.36)
			(layers "B.Paste")
			(roundrect_rratio 0.25)
		)
		(pad "1" smd roundrect
			(at -0.321 0.002)
			(size 0.46 0.4)
			(layers "B.Cu" "B.Mask")
			(roundrect_rratio 0.25)
			(net 460 "1V8_SYS")
			(pintype "passive")
		)
		(pad "2" smd roundrect
			(at 0.32 0.002)
			(size 0.46 0.4)
			(layers "B.Cu" "B.Mask")
			(roundrect_rratio 0.25)
			(net 5 "GND")
			(pintype "passive")
		)
	)
	(footprint "antmicro-footprints:C_0201"
		(layer "B.Cu")
		(at 165.036328 90.625 180)
		(descr "Capacitor SMD 0201")
		(tags "capacitor SMD 0201")
		(property "Reference" "C71"
			(at -2.463672 -0.375 0)
			(layer "B.SilkS")
			(effects
				(font
					(size 0.7 0.7)
					(thickness 0.15)
				)
				(justify left bottom mirror)
			)
		)
		(property "Value" "C_100n_0201"
			(at 0 -1.4 0)
			(layer "B.Fab")
			(effects
				(font
					(size 0.7 0.7)
					(thickness 0.15)
				)
				(justify left bottom mirror)
			)
		)
		(property "Description" " "
			(at 0 0 180)
			(layer "F.Fab")
			(hide yes)
			(effects
				(font
					(size 1.27 1.27)
					(thickness 0.15)
				)
			)
		)
		(property "Author" "Antmicro"
			(at 330.072656 181.25 0)
			(layer "B.Fab")
			(hide yes)
			(effects
				(font
					(size 1 1)
					(thickness 0.15)
				)
				(justify mirror)
			)
		)
		(property "Dielectric" ""
			(at 330.072656 181.25 0)
			(layer "B.Fab")
			(hide yes)
			(effects
				(font
					(size 1 1)
					(thickness 0.15)
				)
				(justify mirror)
			)
		)
		(property "License" "Apache-2.0"
			(at 330.072656 181.25 0)
			(layer "B.Fab")
			(hide yes)
			(effects
				(font
					(size 1 1)
					(thickness 0.15)
				)
				(justify mirror)
			)
		)
		(property "MPN" "CC0201KRX6S5BB104"
			(at 330.072656 181.25 0)
			(layer "B.Fab")
			(hide yes)
			(effects
				(font
					(size 1 1)
					(thickness 0.15)
				)
				(justify mirror)
			)
		)
		(property "Manufacturer" "Yaego"
			(at 330.072656 181.25 0)
			(layer "B.Fab")
			(hide yes)
			(effects
				(font
					(size 1 1)
					(thickness 0.15)
				)
				(justify mirror)
			)
		)
		(property "Val" "100n"
			(at 330.072656 181.25 0)
			(layer "B.Fab")
			(hide yes)
			(effects
				(font
					(size 1 1)
					(thickness 0.15)
				)
				(justify mirror)
			)
		)
		(property "Voltage" ""
			(at 330.072656 181.25 0)
			(layer "B.Fab")
			(hide yes)
			(effects
				(font
					(size 1 1)
					(thickness 0.15)
				)
				(justify mirror)
			)
		)
		(sheetname "FPGA power")
		(sheetfile "fpga-power.kicad_sch")
		(attr smd)
		(fp_rect
			(start -0.72 0.38)
			(end 0.72 -0.38)
			(stroke
				(width 0.05)
				(type solid)
			)
			(fill no)
			(layer "B.CrtYd")
		)
		(fp_rect
			(start 0.3 -0.15)
			(end -0.301 0.149)
			(stroke
				(width 0.15)
				(type solid)
			)
			(fill no)
			(layer "B.Fab")
		)
		(pad "" smd roundrect
			(at -0.349 0.002 180)
			(size 0.318 0.36)
			(layers "B.Paste")
			(roundrect_rratio 0.25)
		)
		(pad "" smd roundrect
			(at 0.341 0.002 180)
			(size 0.318 0.36)
			(layers "B.Paste")
			(roundrect_rratio 0.25)
		)
		(pad "1" smd roundrect
			(at -0.321 0.002 180)
			(size 0.46 0.4)
			(layers "B.Cu" "B.Mask")
			(roundrect_rratio 0.25)
			(net 460 "1V8_SYS")
			(pintype "passive")
		)
		(pad "2" smd roundrect
			(at 0.32 0.002 180)
			(size 0.46 0.4)
			(layers "B.Cu" "B.Mask")
			(roundrect_rratio 0.25)
			(net 5 "GND")
			(pintype "passive")
		)
	)
	(footprint "antmicro-footprints:C_0201"
		(layer "B.Cu")
		(at 164.336328 92.497157 90)
		(descr "Capacitor SMD 0201")
		(tags "capacitor SMD 0201")
		(property "Reference" "C49"
			(at 0.997157 1.163672 270)
			(layer "B.SilkS")
			(effects
				(font
					(size 0.7 0.7)
					(thickness 0.15)
				)
				(justify left bottom mirror)
			)
		)
		(property "Value" "C_100n_0201"
			(at 0 -1.4 270)
			(layer "B.Fab")
			(effects
				(font
					(size 0.7 0.7)
					(thickness 0.15)
				)
				(justify left bottom mirror)
			)
		)
		(property "Description" " "
			(at 0 0 90)
			(layer "F.Fab")
			(hide yes)
			(effects
				(font
					(size 1.27 1.27)
					(thickness 0.15)
				)
			)
		)
		(property "Author" "Antmicro"
			(at 256.833485 -71.839171 0)
			(layer "B.Fab")
			(hide yes)
			(effects
				(font
					(size 1 1)
					(thickness 0.15)
				)
				(justify mirror)
			)
		)
		(property "Dielectric" ""
			(at 256.833485 -71.839171 0)
			(layer "B.Fab")
			(hide yes)
			(effects
				(font
					(size 1 1)
					(thickness 0.15)
				)
				(justify mirror)
			)
		)
		(property "License" "Apache-2.0"
			(at 256.833485 -71.839171 0)
			(layer "B.Fab")
			(hide yes)
			(effects
				(font
					(size 1 1)
					(thickness 0.15)
				)
				(justify mirror)
			)
		)
		(property "MPN" "CC0201KRX6S5BB104"
			(at 256.833485 -71.839171 0)
			(layer "B.Fab")
			(hide yes)
			(effects
				(font
					(size 1 1)
					(thickness 0.15)
				)
				(justify mirror)
			)
		)
		(property "Manufacturer" "Yaego"
			(at 256.833485 -71.839171 0)
			(layer "B.Fab")
			(hide yes)
			(effects
				(font
					(size 1 1)
					(thickness 0.15)
				)
				(justify mirror)
			)
		)
		(property "Val" "100n"
			(at 256.833485 -71.839171 0)
			(layer "B.Fab")
			(hide yes)
			(effects
				(font
					(size 1 1)
					(thickness 0.15)
				)
				(justify mirror)
			)
		)
		(property "Voltage" ""
			(at 256.833485 -71.839171 0)
			(layer "B.Fab")
			(hide yes)
			(effects
				(font
					(size 1 1)
					(thickness 0.15)
				)
				(justify mirror)
			)
		)
		(sheetname "FPGA power")
		(sheetfile "fpga-power.kicad_sch")
		(attr smd)
		(fp_rect
			(start -0.72 0.38)
			(end 0.72 -0.38)
			(stroke
				(width 0.05)
				(type solid)
			)
			(fill no)
			(layer "B.CrtYd")
		)
		(fp_rect
			(start 0.3 -0.15)
			(end -0.301 0.149)
			(stroke
				(width 0.15)
				(type solid)
			)
			(fill no)
			(layer "B.Fab")
		)
		(pad "" smd roundrect
			(at -0.349 0.002 90)
			(size 0.318 0.36)
			(layers "B.Paste")
			(roundrect_rratio 0.25)
		)
		(pad "" smd roundrect
			(at 0.341 0.002 90)
			(size 0.318 0.36)
			(layers "B.Paste")
			(roundrect_rratio 0.25)
		)
		(pad "1" smd roundrect
			(at -0.321 0.002 90)
			(size 0.46 0.4)
			(layers "B.Cu" "B.Mask")
			(roundrect_rratio 0.25)
			(net 460 "1V8_SYS")
			(pintype "passive")
		)
		(pad "2" smd roundrect
			(at 0.32 0.002 90)
			(size 0.46 0.4)
			(layers "B.Cu" "B.Mask")
			(roundrect_rratio 0.25)
			(net 5 "GND")
			(pintype "passive")
		)
	)
	(footprint "antmicro-footprints:C_0201"
		(layer "B.Cu")
		(at 171.511328 96.372157)
		(descr "Capacitor SMD 0201")
		(tags "capacitor SMD 0201")
		(property "Reference" "C75"
			(at -0.511328 0.427843 180)
			(layer "B.SilkS")
			(effects
				(font
					(size 0.7 0.7)
					(thickness 0.15)
				)
				(justify left bottom mirror)
			)
		)
		(property "Value" "C_100n_0201"
			(at 0 -1.4 180)
			(layer "B.Fab")
			(effects
				(font
					(size 0.7 0.7)
					(thickness 0.15)
				)
				(justify left bottom mirror)
			)
		)
		(property "Description" " "
			(at 0 0 0)
			(layer "F.Fab")
			(hide yes)
			(effects
				(font
					(size 1.27 1.27)
					(thickness 0.15)
				)
			)
		)
		(property "Author" "Antmicro"
			(at 0 0 0)
			(layer "B.Fab")
			(hide yes)
			(effects
				(font
					(size 1 1)
					(thickness 0.15)
				)
				(justify mirror)
			)
		)
		(property "Dielectric" ""
			(at 0 0 0)
			(layer "B.Fab")
			(hide yes)
			(effects
				(font
					(size 1 1)
					(thickness 0.15)
				)
				(justify mirror)
			)
		)
		(property "License" "Apache-2.0"
			(at 0 0 0)
			(layer "B.Fab")
			(hide yes)
			(effects
				(font
					(size 1 1)
					(thickness 0.15)
				)
				(justify mirror)
			)
		)
		(property "MPN" "CC0201KRX6S5BB104"
			(at 0 0 0)
			(layer "B.Fab")
			(hide yes)
			(effects
				(font
					(size 1 1)
					(thickness 0.15)
				)
				(justify mirror)
			)
		)
		(property "Manufacturer" "Yaego"
			(at 0 0 0)
			(layer "B.Fab")
			(hide yes)
			(effects
				(font
					(size 1 1)
					(thickness 0.15)
				)
				(justify mirror)
			)
		)
		(property "Val" "100n"
			(at 0 0 0)
			(layer "B.Fab")
			(hide yes)
			(effects
				(font
					(size 1 1)
					(thickness 0.15)
				)
				(justify mirror)
			)
		)
		(property "Voltage" ""
			(at 0 0 0)
			(layer "B.Fab")
			(hide yes)
			(effects
				(font
					(size 1 1)
					(thickness 0.15)
				)
				(justify mirror)
			)
		)
		(sheetname "FPGA power")
		(sheetfile "fpga-power.kicad_sch")
		(attr smd)
		(fp_rect
			(start -0.72 0.38)
			(end 0.72 -0.38)
			(stroke
				(width 0.05)
				(type solid)
			)
			(fill no)
			(layer "B.CrtYd")
		)
		(fp_rect
			(start 0.3 -0.15)
			(end -0.301 0.149)
			(stroke
				(width 0.15)
				(type solid)
			)
			(fill no)
			(layer "B.Fab")
		)
		(pad "" smd roundrect
			(at -0.349 0.002)
			(size 0.318 0.36)
			(layers "B.Paste")
			(roundrect_rratio 0.25)
		)
		(pad "" smd roundrect
			(at 0.341 0.002)
			(size 0.318 0.36)
			(layers "B.Paste")
			(roundrect_rratio 0.25)
		)
		(pad "1" smd roundrect
			(at -0.321 0.002)
			(size 0.46 0.4)
			(layers "B.Cu" "B.Mask")
			(roundrect_rratio 0.25)
			(net 460 "1V8_SYS")
			(pintype "passive")
		)
		(pad "2" smd roundrect
			(at 0.32 0.002)
			(size 0.46 0.4)
			(layers "B.Cu" "B.Mask")
			(roundrect_rratio 0.25)
			(net 5 "GND")
			(pintype "passive")
		)
	)
	(footprint "antmicro-footprints:C_0201"
		(layer "B.Cu")
		(at 165.536328 96.372157 180)
		(descr "Capacitor SMD 0201")
		(tags "capacitor SMD 0201")
		(property "Reference" "C53"
			(at -1.063672 -1.127843 0)
			(layer "B.SilkS")
			(effects
				(font
					(size 0.7 0.7)
					(thickness 0.15)
				)
				(justify left bottom mirror)
			)
		)
		(property "Value" "C_100n_0201"
			(at 0 -1.4 0)
			(layer "B.Fab")
			(effects
				(font
					(size 0.7 0.7)
					(thickness 0.15)
				)
				(justify left bottom mirror)
			)
		)
		(property "Description" " "
			(at 0 0 180)
			(layer "F.Fab")
			(hide yes)
			(effects
				(font
					(size 1.27 1.27)
					(thickness 0.15)
				)
			)
		)
		(property "Author" "Antmicro"
			(at 331.072656 192.744314 0)
			(layer "B.Fab")
			(hide yes)
			(effects
				(font
					(size 1 1)
					(thickness 0.15)
				)
				(justify mirror)
			)
		)
		(property "Dielectric" ""
			(at 331.072656 192.744314 0)
			(layer "B.Fab")
			(hide yes)
			(effects
				(font
					(size 1 1)
					(thickness 0.15)
				)
				(justify mirror)
			)
		)
		(property "License" "Apache-2.0"
			(at 331.072656 192.744314 0)
			(layer "B.Fab")
			(hide yes)
			(effects
				(font
					(size 1 1)
					(thickness 0.15)
				)
				(justify mirror)
			)
		)
		(property "MPN" "CC0201KRX6S5BB104"
			(at 331.072656 192.744314 0)
			(layer "B.Fab")
			(hide yes)
			(effects
				(font
					(size 1 1)
					(thickness 0.15)
				)
				(justify mirror)
			)
		)
		(property "Manufacturer" "Yaego"
			(at 331.072656 192.744314 0)
			(layer "B.Fab")
			(hide yes)
			(effects
				(font
					(size 1 1)
					(thickness 0.15)
				)
				(justify mirror)
			)
		)
		(property "Val" "100n"
			(at 331.072656 192.744314 0)
			(layer "B.Fab")
			(hide yes)
			(effects
				(font
					(size 1 1)
					(thickness 0.15)
				)
				(justify mirror)
			)
		)
		(property "Voltage" ""
			(at 331.072656 192.744314 0)
			(layer "B.Fab")
			(hide yes)
			(effects
				(font
					(size 1 1)
					(thickness 0.15)
				)
				(justify mirror)
			)
		)
		(sheetname "FPGA power")
		(sheetfile "fpga-power.kicad_sch")
		(attr smd)
		(fp_rect
			(start -0.72 0.38)
			(end 0.72 -0.38)
			(stroke
				(width 0.05)
				(type solid)
			)
			(fill no)
			(layer "B.CrtYd")
		)
		(fp_rect
			(start 0.3 -0.15)
			(end -0.301 0.149)
			(stroke
				(width 0.15)
				(type solid)
			)
			(fill no)
			(layer "B.Fab")
		)
		(pad "" smd roundrect
			(at -0.349 0.002 180)
			(size 0.318 0.36)
			(layers "B.Paste")
			(roundrect_rratio 0.25)
		)
		(pad "" smd roundrect
			(at 0.341 0.002 180)
			(size 0.318 0.36)
			(layers "B.Paste")
			(roundrect_rratio 0.25)
		)
		(pad "1" smd roundrect
			(at -0.321 0.002 180)
			(size 0.46 0.4)
			(layers "B.Cu" "B.Mask")
			(roundrect_rratio 0.25)
			(net 460 "1V8_SYS")
			(pintype "passive")
		)
		(pad "2" smd roundrect
			(at 0.32 0.002 180)
			(size 0.46 0.4)
			(layers "B.Cu" "B.Mask")
			(roundrect_rratio 0.25)
			(net 5 "GND")
			(pintype "passive")
		)
	)
	(footprint "antmicro-footprints:C_0201"
		(layer "B.Cu")
		(at 164.336328 97.997157 -90)
		(descr "Capacitor SMD 0201")
		(tags "capacitor SMD 0201")
		(property "Reference" "C88"
			(at -0.797157 0.336328 90)
			(layer "B.SilkS")
			(effects
				(font
					(size 0.7 0.7)
					(thickness 0.15)
				)
				(justify left bottom mirror)
			)
		)
		(property "Value" "C_100n_0201"
			(at 0 -1.4 90)
			(layer "B.Fab")
			(effects
				(font
					(size 0.7 0.7)
					(thickness 0.15)
				)
				(justify left bottom mirror)
			)
		)
		(property "Description" " "
			(at 0 0 270)
			(layer "F.Fab")
			(hide yes)
			(effects
				(font
					(size 1.27 1.27)
					(thickness 0.15)
				)
			)
		)
		(property "Author" "Antmicro"
			(at 66.339171 262.333485 0)
			(layer "B.Fab")
			(hide yes)
			(effects
				(font
					(size 1 1)
					(thickness 0.15)
				)
				(justify mirror)
			)
		)
		(property "Dielectric" ""
			(at 66.339171 262.333485 0)
			(layer "B.Fab")
			(hide yes)
			(effects
				(font
					(size 1 1)
					(thickness 0.15)
				)
				(justify mirror)
			)
		)
		(property "License" "Apache-2.0"
			(at 66.339171 262.333485 0)
			(layer "B.Fab")
			(hide yes)
			(effects
				(font
					(size 1 1)
					(thickness 0.15)
				)
				(justify mirror)
			)
		)
		(property "MPN" "CC0201KRX6S5BB104"
			(at 66.339171 262.333485 0)
			(layer "B.Fab")
			(hide yes)
			(effects
				(font
					(size 1 1)
					(thickness 0.15)
				)
				(justify mirror)
			)
		)
		(property "Manufacturer" "Yaego"
			(at 66.339171 262.333485 0)
			(layer "B.Fab")
			(hide yes)
			(effects
				(font
					(size 1 1)
					(thickness 0.15)
				)
				(justify mirror)
			)
		)
		(property "Val" "100n"
			(at 66.339171 262.333485 0)
			(layer "B.Fab")
			(hide yes)
			(effects
				(font
					(size 1 1)
					(thickness 0.15)
				)
				(justify mirror)
			)
		)
		(property "Voltage" ""
			(at 66.339171 262.333485 0)
			(layer "B.Fab")
			(hide yes)
			(effects
				(font
					(size 1 1)
					(thickness 0.15)
				)
				(justify mirror)
			)
		)
		(sheetname "FPGA power")
		(sheetfile "fpga-power.kicad_sch")
		(attr smd)
		(fp_rect
			(start -0.72 0.38)
			(end 0.72 -0.38)
			(stroke
				(width 0.05)
				(type solid)
			)
			(fill no)
			(layer "B.CrtYd")
		)
		(fp_rect
			(start 0.3 -0.15)
			(end -0.301 0.149)
			(stroke
				(width 0.15)
				(type solid)
			)
			(fill no)
			(layer "B.Fab")
		)
		(pad "" smd roundrect
			(at -0.349 0.002 270)
			(size 0.318 0.36)
			(layers "B.Paste")
			(roundrect_rratio 0.25)
		)
		(pad "" smd roundrect
			(at 0.341 0.002 270)
			(size 0.318 0.36)
			(layers "B.Paste")
			(roundrect_rratio 0.25)
		)
		(pad "1" smd roundrect
			(at -0.321 0.002 270)
			(size 0.46 0.4)
			(layers "B.Cu" "B.Mask")
			(roundrect_rratio 0.25)
			(net 465 "1V0_SYS")
			(pintype "passive")
		)
		(pad "2" smd roundrect
			(at 0.32 0.002 270)
			(size 0.46 0.4)
			(layers "B.Cu" "B.Mask")
			(roundrect_rratio 0.25)
			(net 5 "GND")
			(pintype "passive")
		)
	)
)
